(kicad_pcb
	(version 20221018)
	(generator pcbnew)
	(general
    (thickness 1.518)
  )
	(paper "A4")
	(title_block
    (title "Kria K26 Devboard")
    (date "2024-03-26")
    (rev "1.2.5")
    (comment 1 "www.antmicro.com")
    (comment 2 "Antmicro Ltd.")
		(comment 9 "footprints 60-67 of 660")
	)
	(layers
    (0 "F.Cu" mixed)
    (1 "In1.Cu" power)
    (2 "In2.Cu" mixed)
    (3 "In3.Cu" power)
    (4 "In4.Cu" mixed)
    (5 "In5.Cu" power)
    (6 "In6.Cu" mixed)
    (31 "B.Cu" power)
    (32 "B.Adhes" user "B.Adhesive")
    (33 "F.Adhes" user "F.Adhesive")
    (34 "B.Paste" user)
    (35 "F.Paste" user)
    (36 "B.SilkS" user "B.Silkscreen")
    (37 "F.SilkS" user "F.Silkscreen")
    (38 "B.Mask" user)
    (39 "F.Mask" user)
    (40 "Dwgs.User" user "User.Drawings")
    (41 "Cmts.User" user "User.Comments")
    (42 "Eco1.User" user "User.Eco1")
    (43 "Eco2.User" user "User.Eco2")
    (44 "Edge.Cuts" user)
    (45 "Margin" user)
    (46 "B.CrtYd" user "B.Courtyard")
    (47 "F.CrtYd" user "F.Courtyard")
    (48 "B.Fab" user)
    (49 "F.Fab" user)
  )
	(footprint "kria-k26-devboard-footprints:LED_0603_1608Metric_G" (layer "F.Cu")
    (at 186 137.8 180)
    (descr "LED SMD 0603 Green")
    (tags "LED SMD 0603 Green")
    (property "Author" "Antmicro")
    (property "Color" "Green")
    (property "License" "Apache-2.0")
    (property "MPN" "LG L29K-G2J1-24-Z")
    (property "Manufacturer" "OSRAM")
    (property "Sheetfile" "dc-dc-conventers.kicad_sch")
    (property "Sheetname" "DC/DC conventers")
    (property "ki_description" "LED, Green, SMT, 0603, 20 mA, 2.1 V, 570 nm")
    (property "ki_keywords" "0603, SMT, DIODE, SEMICONDUCTOR, UNICOLOR")
    (attr smd)
    (fp_text reference "D20" (at 1.21 -0.74) (layer "F.SilkS")
        (effects (font (size 0.7 0.7) (thickness 0.15)) (justify right bottom))
    )
    (fp_text value "LED_G_0603_LG_L29K-G2J1-24-Z" (at 0 1.6) (layer "F.Fab") hide
        (effects (font (size 0.7 0.7) (thickness 0.15)) (justify right bottom))
    )
    (fp_text user "License: Apache-2.0" (at -1.31 5.769) (layer "F.Fab") hide
        (effects (font (size 0.7 0.7) (thickness 0.15)) (justify right bottom))
    )
    (fp_text user "${REFERENCE}" (at -1.31 3.769) (layer "F.Fab") hide
        (effects (font (size 0.7 0.7) (thickness 0.15)) (justify right bottom))
    )
    (fp_text user "Author: Antmicro" (at -1.31 4.769) (layer "F.Fab") hide
        (effects (font (size 0.7 0.7) (thickness 0.15)) (justify right bottom))
    )
    (fp_line (start -0.27 -0.35) (end 0.27 -0.35)
      (stroke (width 0.15) (type solid)) (layer "F.SilkS"))
    (fp_line (start -0.27 0.351) (end 0.27 0.351)
      (stroke (width 0.15) (type solid)) (layer "F.SilkS"))
    (fp_line (start -0.106328 -0.200008) (end -0.106328 0.199992)
      (stroke (width 0.1) (type solid)) (layer "F.SilkS"))
    (fp_line (start -0.106328 -0.200008) (end 0.093672 -0.000008)
      (stroke (width 0.1) (type solid)) (layer "F.SilkS"))
    (fp_line (start -0.106328 -0.000008) (end -0.29 0)
      (stroke (width 0.1) (type solid)) (layer "F.SilkS"))
    (fp_line (start 0.093672 -0.200008) (end 0.093672 0.199992)
      (stroke (width 0.1) (type solid)) (layer "F.SilkS"))
    (fp_line (start 0.093672 -0.000008) (end -0.106328 0.199992)
      (stroke (width 0.1) (type solid)) (layer "F.SilkS"))
    (fp_line (start 0.093672 -0.000008) (end 0.293672 -0.000008)
      (stroke (width 0.1) (type solid)) (layer "F.SilkS"))
    (fp_line (start 1.25 0.32) (end 1.25 -0.32)
      (stroke (width 0.15) (type solid)) (layer "F.SilkS"))
    (fp_rect (start 1.26 0.65) (end -1.26 -0.65)
      (stroke (width 0.05) (type solid)) (fill none) (layer "F.CrtYd"))
    (fp_line (start -0.599 0) (end -0.201 0)
      (stroke (width 0.15) (type solid)) (layer "F.Fab"))
    (fp_line (start -0.201 -0.2) (end -0.201 0)
      (stroke (width 0.15) (type solid)) (layer "F.Fab"))
    (fp_line (start -0.201 0) (end -0.201 0.202)
      (stroke (width 0.15) (type solid)) (layer "F.Fab"))
    (fp_line (start -0.201 0.202) (end 0.101 0)
      (stroke (width 0.15) (type solid)) (layer "F.Fab"))
    (fp_line (start 0.101 0) (end -0.201 -0.2)
      (stroke (width 0.15) (type solid)) (layer "F.Fab"))
    (fp_line (start 0.199 -0.2) (end 0.199 -0.1)
      (stroke (width 0.15) (type solid)) (layer "F.Fab"))
    (fp_line (start 0.199 0) (end 0.597 0)
      (stroke (width 0.15) (type solid)) (layer "F.Fab"))
    (fp_line (start 0.199 0.202) (end 0.199 -0.1)
      (stroke (width 0.15) (type solid)) (layer "F.Fab"))
    (fp_rect (start -0.848 -0.4) (end 0.85 0.402)
      (stroke (width 0.15) (type solid)) (fill none) (layer "F.Fab"))
    (pad "1" smd rect (at -0.75 0) (size 0.8 0.8) (layers "F.Cu" "F.Paste" "F.Mask")
      (net 192 "Net-(D20-Pad1)") (pintype "passive"))
    (pad "2" smd rect (at 0.75 0) (size 0.8 0.8) (layers "F.Cu" "F.Paste" "F.Mask")
      (net 340 "Net-(Q15-C)") (pinfunction "2") (pintype "passive"))
  )
	(footprint "kria-k26-devboard-footprints:C_0603_1608Metric" (layer "F.Cu")
    (at 191.2 135.846752 90)
    (descr "Capacitor SMD 0603")
    (tags "capacitor 0603")
    (property "Author" "Antmicro")
    (property "Dielectric" "")
    (property "License" "Apache-2.0")
    (property "MPN" "GRM188R60J226MEA0D")
    (property "Manufacturer" "Murata")
    (property "Sheetfile" "dc-dc-conventers.kicad_sch")
    (property "Sheetname" "DC/DC conventers")
    (property "Val" "22u")
    (property "Voltage" "")
    (property "ki_description" " ")
    (attr smd)
    (fp_text reference "C226" (at -6.613248 0.34 90) (layer "F.SilkS")
        (effects (font (size 0.7 0.7) (thickness 0.15)) (justify left bottom))
    )
    (fp_text value "C_22u_0603" (at 0 1.6 90) (layer "F.Fab") hide
        (effects (font (size 0.7 0.7) (thickness 0.15)) (justify left bottom))
    )
    (fp_text user "${REFERENCE}" (at -1.682 3.895 90) (layer "F.Fab") hide
        (effects (font (size 0.7 0.7) (thickness 0.15)) (justify left bottom))
    )
    (fp_text user "Author: Antmicro" (at -1.682 4.894 90) (layer "F.Fab") hide
        (effects (font (size 0.7 0.7) (thickness 0.15)) (justify left bottom))
    )
    (fp_text user "License: Apache-2.0" (at -1.682 5.895 90) (layer "F.Fab") hide
        (effects (font (size 0.7 0.7) (thickness 0.15)) (justify left bottom))
    )
    (fp_line (start -0.3 -0.3) (end 0.3 -0.3)
      (stroke (width 0.15) (type solid)) (layer "F.SilkS"))
    (fp_line (start -0.3 0.3) (end 0.3 0.3)
      (stroke (width 0.15) (type solid)) (layer "F.SilkS"))
    (fp_rect (start -1.24 -0.7) (end 1.24 0.7)
      (stroke (width 0.05) (type solid)) (fill none) (layer "F.CrtYd"))
    (fp_rect (start -0.8 -0.4) (end 0.8 0.4)
      (stroke (width 0.15) (type solid)) (fill none) (layer "F.Fab"))
    (pad "1" smd roundrect (at -0.7 0 90) (size 0.6 0.8) (layers "F.Cu" "F.Paste" "F.Mask") (roundrect_rratio 0.2)
      (net 771 "/Power Supply/DC/DC conventers/PL_1V2_OUT") (pintype "passive"))
    (pad "2" smd roundrect (at 0.7 0 90) (size 0.6 0.8) (layers "F.Cu" "F.Paste" "F.Mask") (roundrect_rratio 0.2)
      (net 1 "GND") (pintype "passive"))
  )
	(footprint "kria-k26-devboard-footprints:C_0603_1608Metric" (layer "F.Cu")
    (at 189.9 133.1 -90)
    (descr "Capacitor SMD 0603")
    (tags "capacitor 0603")
    (property "Author" "Antmicro")
    (property "Dielectric" "")
    (property "License" "Apache-2.0")
    (property "MPN" "C1608X5R1E106M080AC")
    (property "Manufacturer" "TDK")
    (property "Sheetfile" "dc-dc-conventers.kicad_sch")
    (property "Sheetname" "DC/DC conventers")
    (property "Val" "10u/25V")
    (property "Voltage" "")
    (property "ki_description" " ")
    (attr smd)
    (fp_text reference "C220" (at 0.09 -1.63 -90) (layer "F.SilkS")
        (effects (font (size 0.7 0.7) (thickness 0.15)) (justify left bottom))
    )
    (fp_text value "C_10u_25V_0603" (at 0 1.6 -90) (layer "F.Fab") hide
        (effects (font (size 0.7 0.7) (thickness 0.15)) (justify left bottom))
    )
    (fp_text user "License: Apache-2.0" (at -1.682 5.895 -90) (layer "F.Fab") hide
        (effects (font (size 0.7 0.7) (thickness 0.15)) (justify left bottom))
    )
    (fp_text user "${REFERENCE}" (at -1.682 3.895 -90) (layer "F.Fab") hide
        (effects (font (size 0.7 0.7) (thickness 0.15)) (justify left bottom))
    )
    (fp_text user "Author: Antmicro" (at -1.682 4.894 -90) (layer "F.Fab") hide
        (effects (font (size 0.7 0.7) (thickness 0.15)) (justify left bottom))
    )
    (fp_line (start -0.3 -0.3) (end 0.3 -0.3)
      (stroke (width 0.15) (type solid)) (layer "F.SilkS"))
    (fp_line (start -0.3 0.3) (end 0.3 0.3)
      (stroke (width 0.15) (type solid)) (layer "F.SilkS"))
    (fp_rect (start -1.24 -0.7) (end 1.24 0.7)
      (stroke (width 0.05) (type solid)) (fill none) (layer "F.CrtYd"))
    (fp_rect (start -0.8 -0.4) (end 0.8 0.4)
      (stroke (width 0.15) (type solid)) (fill none) (layer "F.Fab"))
    (pad "1" smd roundrect (at -0.7 0 270) (size 0.6 0.8) (layers "F.Cu" "F.Paste" "F.Mask") (roundrect_rratio 0.2)
      (net 14 "/Power Supply/DC/DC conventers/DC_MAIN_BUS") (pintype "passive"))
    (pad "2" smd roundrect (at 0.7 0 270) (size 0.6 0.8) (layers "F.Cu" "F.Paste" "F.Mask") (roundrect_rratio 0.2)
      (net 1 "GND") (pintype "passive"))
  )
	(footprint "kria-k26-devboard-footprints:C_0603_1608Metric" (layer "F.Cu")
    (at 189.985356 135.846752 90)
    (descr "Capacitor SMD 0603")
    (tags "capacitor 0603")
    (property "Author" "Antmicro")
    (property "Dielectric" "")
    (property "License" "Apache-2.0")
    (property "MPN" "GRM188R60J226MEA0D")
    (property "Manufacturer" "Murata")
    (property "Sheetfile" "dc-dc-conventers.kicad_sch")
    (property "Sheetname" "DC/DC conventers")
    (property "Val" "22u")
    (property "Voltage" "")
    (property "ki_description" " ")
    (attr smd)
    (fp_text reference "C224" (at -6.613248 0.34 90) (layer "F.SilkS")
        (effects (font (size 0.7 0.7) (thickness 0.15)) (justify left bottom))
    )
    (fp_text value "C_22u_0603" (at 0 1.6 90) (layer "F.Fab") hide
        (effects (font (size 0.7 0.7) (thickness 0.15)) (justify left bottom))
    )
    (fp_text user "${REFERENCE}" (at -1.682 3.895 90) (layer "F.Fab") hide
        (effects (font (size 0.7 0.7) (thickness 0.15)) (justify left bottom))
    )
    (fp_text user "License: Apache-2.0" (at -1.682 5.895 90) (layer "F.Fab") hide
        (effects (font (size 0.7 0.7) (thickness 0.15)) (justify left bottom))
    )
    (fp_text user "Author: Antmicro" (at -1.682 4.894 90) (layer "F.Fab") hide
        (effects (font (size 0.7 0.7) (thickness 0.15)) (justify left bottom))
    )
    (fp_line (start -0.3 -0.3) (end 0.3 -0.3)
      (stroke (width 0.15) (type solid)) (layer "F.SilkS"))
    (fp_line (start -0.3 0.3) (end 0.3 0.3)
      (stroke (width 0.15) (type solid)) (layer "F.SilkS"))
    (fp_rect (start -1.24 -0.7) (end 1.24 0.7)
      (stroke (width 0.05) (type solid)) (fill none) (layer "F.CrtYd"))
    (fp_rect (start -0.8 -0.4) (end 0.8 0.4)
      (stroke (width 0.15) (type solid)) (fill none) (layer "F.Fab"))
    (pad "1" smd roundrect (at -0.7 0 90) (size 0.6 0.8) (layers "F.Cu" "F.Paste" "F.Mask") (roundrect_rratio 0.2)
      (net 771 "/Power Supply/DC/DC conventers/PL_1V2_OUT") (pintype "passive"))
    (pad "2" smd roundrect (at 0.7 0 90) (size 0.6 0.8) (layers "F.Cu" "F.Paste" "F.Mask") (roundrect_rratio 0.2)
      (net 1 "GND") (pintype "passive"))
  )
	(footprint "kria-k26-devboard-footprints:L_0806_2016Metric" (layer "F.Cu")
    (at 187.8 135.925001)
    (property "Author" "Antmicro")
    (property "IMax" "")
    (property "ISat" "")
    (property "License" "Apache-2.0")
    (property "MPN" "SRP2010-1R0M")
    (property "Manufacturer" "Bourns")
    (property "Sheetfile" "dc-dc-conventers.kicad_sch")
    (property "Sheetname" "DC/DC conventers")
    (property "Size" "2.0x1.6")
    (property "Val" "1u/2.6A")
    (attr smd)
    (fp_text reference "L9" (at 0.98 -4.225001) (layer "F.SilkS")
        (effects (font (size 0.7 0.7) (thickness 0.15)) (justify left bottom))
    )
    (fp_text value "L_1u_2.6A_0806" (at 0 2) (layer "F.Fab") hide
        (effects (font (size 0.7 0.7) (thickness 0.15)) (justify left bottom))
    )
    (fp_text user "Author: Antmicro" (at -1.9 4.4) (layer "F.Fab") hide
        (effects (font (size 0.7 0.7) (thickness 0.15)) (justify left bottom))
    )
    (fp_text user "License: Apache-2.0" (at -1.9 5.75) (layer "F.Fab") hide
        (effects (font (size 0.7 0.7) (thickness 0.15)) (justify left bottom))
    )
    (fp_text user "${REFERENCE}" (at -1.9 3.1) (layer "F.Fab") hide
        (effects (font (size 0.7 0.7) (thickness 0.15)) (justify left bottom))
    )
    (fp_line (start -0.301 0.9) (end 0.299 0.9)
      (stroke (width 0.15) (type solid)) (layer "F.SilkS"))
    (fp_line (start -0.3 -0.9) (end 0.298 -0.9)
      (stroke (width 0.15) (type solid)) (layer "F.SilkS"))
    (fp_rect (start -1.75 -1.05) (end 1.75 1.05)
      (stroke (width 0.05) (type solid)) (fill none) (layer "F.CrtYd"))
    (fp_rect (start -0.951 -0.882) (end 0.949 0.875)
      (stroke (width 0.15) (type solid)) (fill none) (layer "F.Fab"))
    (pad "1" smd roundrect (at -1.1 -0.001) (size 1 1.8) (layers "F.Cu" "F.Paste" "F.Mask") (roundrect_rratio 0.15)
      (net 316 "/Power Supply/DC/DC conventers/SW_PL_1V2") (pintype "passive"))
    (pad "2" smd roundrect (at 1.1 -0.001) (size 1 1.8) (layers "F.Cu" "F.Paste" "F.Mask") (roundrect_rratio 0.15)
      (net 771 "/Power Supply/DC/DC conventers/PL_1V2_OUT") (pintype "passive"))
  )
	(footprint "kria-k26-devboard-footprints:R_0402_1005Metric" (layer "F.Cu")
    (at 184.524999 131.985 90)
    (descr "Resistor SMD 0402")
    (tags "resistor SMD 0402")
    (property "Author" "Antmicro")
    (property "License" "Apache-2.0")
    (property "MPN" "CR0402-FX-4991GLF")
    (property "Manufacturer" "Bourns")
    (property "Sheetfile" "dc-dc-conventers.kicad_sch")
    (property "Sheetname" "DC/DC conventers")
    (property "Tolerance" "1%")
    (property "Val" "4k99")
    (property "ki_description" "4k99 resistor in 0402 package with 1% tolerance")
    (attr smd)
    (fp_text reference "R146" (at -0.295 -0.604999 90) (layer "F.SilkS")
        (effects (font (size 0.7 0.7) (thickness 0.15)) (justify left bottom))
    )
    (fp_text value "R_4k99_0402" (at 0 1.4 90) (layer "F.Fab") hide
        (effects (font (size 0.7 0.7) (thickness 0.15)) (justify left bottom))
    )
    (fp_text user "Author: Antmicro" (at -0.95 4.169 90) (layer "F.Fab") hide
        (effects (font (size 0.7 0.7) (thickness 0.15)) (justify left bottom))
    )
    (fp_text user "${REFERENCE}" (at -0.95 3.168 90) (layer "F.Fab") hide
        (effects (font (size 0.7 0.7) (thickness 0.15)) (justify left bottom))
    )
    (fp_text user "License: Apache-2.0" (at -0.95 5.169 90) (layer "F.Fab") hide
        (effects (font (size 0.7 0.7) (thickness 0.15)) (justify left bottom))
    )
    (fp_rect (start -0.93 -0.47) (end 0.93 0.47)
      (stroke (width 0.05) (type solid)) (fill none) (layer "F.CrtYd"))
    (fp_rect (start -0.5 -0.25) (end 0.5 0.25)
      (stroke (width 0.15) (type solid)) (fill none) (layer "F.Fab"))
    (pad "1" smd roundrect (at -0.485 0 90) (size 0.59 0.64) (layers "F.Cu" "F.Paste" "F.Mask") (roundrect_rratio 0.25)
      (net 771 "/Power Supply/DC/DC conventers/PL_1V2_OUT") (pintype "passive"))
    (pad "2" smd roundrect (at 0.485 0 90) (size 0.59 0.64) (layers "F.Cu" "F.Paste" "F.Mask") (roundrect_rratio 0.25)
      (net 694 "Net-(U55-FB)") (pintype "passive"))
  )
	(footprint "kria-k26-devboard-footprints:R_0402_1005Metric" (layer "F.Cu")
    (at 186.060355 130.496751)
    (descr "Resistor SMD 0402")
    (tags "resistor SMD 0402")
    (property "Author" "Antmicro")
    (property "License" "Apache-2.0")
    (property "MPN" "CR0402-FX-1002GLF")
    (property "Manufacturer" "Bourns")
    (property "Sheetfile" "dc-dc-conventers.kicad_sch")
    (property "Sheetname" "DC/DC conventers")
    (property "Tolerance" "1%")
    (property "Val" "10k")
    (property "ki_description" "10k resistor in 0402 package with 1% tolerance")
    (attr smd)
    (fp_text reference "R147" (at 0.609645 -0.446751) (layer "F.SilkS")
        (effects (font (size 0.7 0.7) (thickness 0.15)) (justify left bottom))
    )
    (fp_text value "R_10k_0402" (at 0 1.4) (layer "F.Fab") hide
        (effects (font (size 0.7 0.7) (thickness 0.15)) (justify left bottom))
    )
    (fp_text user "${REFERENCE}" (at -0.95 3.168) (layer "F.Fab") hide
        (effects (font (size 0.7 0.7) (thickness 0.15)) (justify left bottom))
    )
    (fp_text user "Author: Antmicro" (at -0.95 4.169) (layer "F.Fab") hide
        (effects (font (size 0.7 0.7) (thickness 0.15)) (justify left bottom))
    )
    (fp_text user "License: Apache-2.0" (at -0.95 5.169) (layer "F.Fab") hide
        (effects (font (size 0.7 0.7) (thickness 0.15)) (justify left bottom))
    )
    (fp_rect (start -0.93 -0.47) (end 0.93 0.47)
      (stroke (width 0.05) (type solid)) (fill none) (layer "F.CrtYd"))
    (fp_rect (start -0.5 -0.25) (end 0.5 0.25)
      (stroke (width 0.15) (type solid)) (fill none) (layer "F.Fab"))
    (pad "1" smd roundrect (at -0.485 0) (size 0.59 0.64) (layers "F.Cu" "F.Paste" "F.Mask") (roundrect_rratio 0.25)
      (net 694 "Net-(U55-FB)") (pintype "passive"))
    (pad "2" smd roundrect (at 0.485 0) (size 0.59 0.64) (layers "F.Cu" "F.Paste" "F.Mask") (roundrect_rratio 0.25)
      (net 1 "GND") (pintype "passive"))
  )
	(footprint "kria-k26-devboard-footprints:C_0402_1005Metric" (layer "F.Cu")
    (at 138.845 136 -90)
    (descr "Capacitor SMD 0402")
    (tags "capacitor SMD 0402")
    (property "Author" "Antmicro")
    (property "Dielectric" "X5R")
    (property "License" "Apache-2.0")
    (property "MPN" "GRM155R61H104KE14D")
    (property "Manufacturer" "Murata")
    (property "Sheetfile" "sd-3-card.kicad_sch")
    (property "Sheetname" "SD 3.0 card")
    (property "Val" "100n")
    (property "Voltage" "50V")
    (property "ki_description" " ")
    (attr smd)
    (fp_text reference "C13" (at 1.05 -1.325 -90) (layer "F.SilkS")
        (effects (font (size 0.7 0.7) (thickness 0.15)) (justify left bottom))
    )
    (fp_text value "C_100n_0402" (at 0 1.4 -90) (layer "F.Fab") hide
        (effects (font (size 0.7 0.7) (thickness 0.15)) (justify left bottom))
    )
    (fp_text user "Author: Antmicro" (at -0.932 4.17 -90) (layer "F.Fab") hide
        (effects (font (size 0.7 0.7) (thickness 0.15)) (justify left bottom))
    )
    (fp_text user "License: Apache-2.0" (at -0.932 5.17 -90) (layer "F.Fab") hide
        (effects (font (size 0.7 0.7) (thickness 0.15)) (justify left bottom))
    )
    (fp_text user "${REFERENCE}" (at -0.932 3.168 -90) (layer "F.Fab") hide
        (effects (font (size 0.7 0.7) (thickness 0.15)) (justify left bottom))
    )
    (fp_rect (start -0.94 -0.47) (end 0.94 0.47)
      (stroke (width 0.05) (type solid)) (fill none) (layer "F.CrtYd"))
    (fp_rect (start -0.499 -0.249) (end 0.499 0.249)
      (stroke (width 0.15) (type solid)) (fill none) (layer "F.Fab"))
    (pad "1" smd roundrect (at -0.484 0 270) (size 0.59 0.64) (layers "F.Cu" "F.Paste" "F.Mask") (roundrect_rratio 0.25)
      (net 17 "PS_1V8") (pintype "passive"))
    (pad "2" smd roundrect (at 0.484 0 270) (size 0.59 0.64) (layers "F.Cu" "F.Paste" "F.Mask") (roundrect_rratio 0.25)
      (net 1 "GND") (pintype "passive"))
  )
)
